# BASEBOARD_FAB2 (Tioga Pass) — schematic netlist excerpt (pin names and nets, part order shuffled) for the footprints in the layout excerpt that follows; sources: Cadence DE-HDL packaged netlist, KiCad conversion of Wiwynn_Tioga_Pass_MB.brd

C25W72  CAP  12.0PF 50V 5% COG  pkg 0402LF  page 252 : A = BMC_VGA_BLUE ; B = GND
C9M9  CAP_A  0.1UF 16V 10% X7R  pkg 0402V  page 198 : A = P12V_STBY ; B = GND
C3N22  CAP_A  1.0UF 6.3V 10% X6S  pkg 0402V  page 130 : A = P1V8_PCH_STBY ; B = GND

(kicad_pcb
	(version 20260206)
	(generator "pcbnew")
	(generator_version "10.0")
	(general
		(thickness 1.6)
		(legacy_teardrops no)
	)
	(paper "A4")
	(title_block
		(title "Wiwynn_Tioga_Pass_MB.brd")
		(comment 1 "Tioga Pass / footprints 2476-2478 of 4770")
	)
	(layers
		(0 "F.Cu" signal "TOP")
		(4 "In1.Cu" signal "L2GND")
		(6 "In2.Cu" signal "L3")
		(8 "In3.Cu" signal "L4GND")
		(10 "In4.Cu" signal "L5")
		(12 "In5.Cu" signal "L6GND")
		(14 "In6.Cu" signal "L7VCC")
		(16 "In7.Cu" signal "L8VCC")
		(18 "In8.Cu" signal "L9GND")
		(20 "In9.Cu" signal "L10")
		(22 "In10.Cu" signal "L11GND")
		(24 "In11.Cu" signal "L12")
		(26 "In12.Cu" signal "L13GND")
		(2 "B.Cu" signal "BOTTOM")
		(9 "F.Adhes" user "F.Adhesive")
		(11 "B.Adhes" user "B.Adhesive")
		(13 "F.Paste" user "Package Geometry/Pastemask Top")
		(15 "B.Paste" user "Package Geometry/Pastemask Bottom")
		(5 "F.SilkS" user "Ref Des/Silkscreen Top")
		(7 "B.SilkS" user "Ref Des/Silkscreen Bottom")
		(1 "F.Mask" user "Board Geometry/Soldermask Top")
		(3 "B.Mask" user "Board Geometry/Soldermask Bottom")
		(17 "Dwgs.User" user "User.Drawings")
		(19 "Cmts.User" user "User.Comments")
		(21 "Eco1.User" user "User.Eco1")
		(23 "Eco2.User" user "User.Eco2")
		(25 "Edge.Cuts" user "Board Geometry/Outline")
		(27 "Margin" user)
		(31 "F.CrtYd" user "Package Geometry/Place Bound Top")
		(29 "B.CrtYd" user "Package Geometry/Place Bound Bottom")
		(35 "F.Fab" user "Ref Des/Assembly Top")
		(33 "B.Fab" user "Ref Des/Assembly Bottom")
	)
	(footprint ""
		(layer "B.Cu")
		(at 385.33705 -105.45445 -90)
		(property "Reference" "C3N22"
			(at 0 0 90)
			(layer "B.SilkS")
			(hide yes)
			(effects
				(font
					(size 1.27 1.27)
				)
				(justify mirror)
			)
		)
		(property "Value" ""
			(at 0 0 90)
			(layer "B.Fab")
			(effects
				(font
					(size 1.27 1.27)
				)
				(justify mirror)
			)
		)
		(duplicate_pad_numbers_are_jumpers no)
		(fp_rect
			(start 0.2794 0.9144)
			(end -0.2794 -0.1143)
			(stroke
				(width 0)
				(type default)
			)
			(fill no)
			(layer "B.CrtYd")
		)
		(fp_line
			(start -0.2794 0.9144)
			(end 0.2794 0.9144)
			(stroke
				(width 0.1)
				(type default)
			)
			(layer "B.Fab")
		)
		(fp_line
			(start 0.2794 0.9144)
			(end 0.2794 -0.1143)
			(stroke
				(width 0.1)
				(type default)
			)
			(layer "B.Fab")
		)
		(fp_line
			(start -0.2794 -0.1143)
			(end -0.2794 0.9144)
			(stroke
				(width 0.1)
				(type default)
			)
			(layer "B.Fab")
		)
		(fp_line
			(start 0.2794 -0.1143)
			(end -0.2794 -0.1143)
			(stroke
				(width 0.1)
				(type default)
			)
			(layer "B.Fab")
		)
		(pad "1" smd custom
			(at 0 0 180)
			(size 0.10414 0.10414)
			(layers "B.Cu" "B.Mask" "B.Paste")
			(net "P1V8_PCH_STBY")
			(options
				(clearance outline)
				(anchor circle)
			)
			(primitives
				(gr_poly
					(pts
						(xy -0.20828 -0.08636) (xy -0.20828 0.08636) (xy -0.08636 0.20828) (xy 0.086614 0.20828) (xy 0.20828 0.086614)
						(xy 0.20828 -0.08636) (xy 0.08636 -0.20828) (xy -0.08636 -0.20828)
					)
					(width 0)
					(fill yes)
				)
			)
		)
		(pad "2" smd custom
			(at 0 0.8001 180)
			(size 0.10414 0.10414)
			(layers "B.Cu" "B.Mask" "B.Paste")
			(net "GND")
			(options
				(clearance outline)
				(anchor circle)
			)
			(primitives
				(gr_poly
					(pts
						(xy -0.20828 -0.08636) (xy -0.20828 0.08636) (xy -0.08636 0.20828) (xy 0.086614 0.20828) (xy 0.20828 0.086614)
						(xy 0.20828 -0.08636) (xy 0.08636 -0.20828) (xy -0.08636 -0.20828)
					)
					(width 0)
					(fill yes)
				)
			)
		)
		(zone
			(layer "B.Cu")
			(hatch none 0.5)
			(connect_pads
				(clearance 0)
			)
			(min_thickness 0.25)
			(keepout
				(tracks not_allowed)
				(vias allowed)
				(pads allowed)
				(copperpour not_allowed)
				(footprints allowed)
			)
			(placement
				(enabled no)
				(sheetname "")
			)
			(fill
				(thermal_gap 0.5)
				(thermal_bridge_width 0.5)
				(island_removal_mode 0)
			)
			(polygon
				(pts
					(xy 385.1275 -105.36682) (xy 384.7465 -105.36682) (xy 384.7465 -105.54208) (xy 385.1275 -105.542334)
				)
			)
		)
		(zone
			(layer "B.Cu")
			(hatch none 0.5)
			(connect_pads
				(clearance 0)
			)
			(min_thickness 0.25)
			(keepout
				(tracks allowed)
				(vias not_allowed)
				(pads allowed)
				(copperpour not_allowed)
				(footprints allowed)
			)
			(placement
				(enabled no)
				(sheetname "")
			)
			(fill
				(thermal_gap 0.5)
				(thermal_bridge_width 0.5)
				(island_removal_mode 0)
			)
			(polygon
				(pts
					(xy 385.1275 -105.36682) (xy 384.7465 -105.36682) (xy 384.7465 -105.54208) (xy 385.1275 -105.542334)
				)
			)
		)
	)
	(footprint ""
		(layer "B.Cu")
		(at 416.179 -22.225)
		(property "Reference" "C25W72"
			(at 0.8382 -0.67818 0)
			(unlocked yes)
			(layer "B.SilkS")
			(effects
				(font
					(size 0.4064 0.254)
					(thickness 0.1524)
				)
				(justify left mirror)
			)
		)
		(property "Value" ""
			(at 0 0 0)
			(layer "B.Fab")
			(effects
				(font
					(size 1.27 1.27)
				)
				(justify mirror)
			)
		)
		(duplicate_pad_numbers_are_jumpers no)
		(fp_poly
			(pts
				(xy -0.3048 -0.1016) (xy -0.3048 0.9906) (xy 0.3048 0.9906) (xy 0.3048 -0.1016)
			)
			(stroke
				(width 0)
				(type default)
			)
			(fill no)
			(layer "B.CrtYd")
		)
		(fp_line
			(start -0.3048 -0.1016)
			(end 0.3048 -0.1016)
			(stroke
				(width 0.1)
				(type default)
			)
			(layer "B.Fab")
		)
		(fp_line
			(start -0.3048 0.9906)
			(end -0.3048 -0.1016)
			(stroke
				(width 0.1)
				(type default)
			)
			(layer "B.Fab")
		)
		(fp_line
			(start 0.3048 -0.1016)
			(end 0.3048 0.9906)
			(stroke
				(width 0.1)
				(type default)
			)
			(layer "B.Fab")
		)
		(fp_line
			(start 0.3048 0.9906)
			(end -0.3048 0.9906)
			(stroke
				(width 0.1)
				(type default)
			)
			(layer "B.Fab")
		)
		(pad "1" smd rect
			(at 0 0 180)
			(size 0.508 0.508)
			(layers "B.Cu" "B.Mask" "B.Paste")
			(net "BMC_VGA_BLUE")
		)
		(pad "2" smd rect
			(at 0 0.889 180)
			(size 0.508 0.508)
			(layers "B.Cu" "B.Mask" "B.Paste")
			(net "GND")
		)
		(zone
			(layer "B.Cu")
			(hatch none 0.5)
			(connect_pads
				(clearance 0)
			)
			(min_thickness 0.25)
			(keepout
				(tracks allowed)
				(vias not_allowed)
				(pads allowed)
				(copperpour not_allowed)
				(footprints allowed)
			)
			(placement
				(enabled no)
				(sheetname "")
			)
			(fill
				(thermal_gap 0.5)
				(thermal_bridge_width 0.5)
				(island_removal_mode 0)
			)
			(polygon
				(pts
					(xy 416.433 -21.971) (xy 415.925 -21.971) (xy 415.925 -21.59) (xy 416.433 -21.59)
				)
			)
		)
		(zone
			(layer "B.Cu")
			(hatch none 0.5)
			(connect_pads
				(clearance 0)
			)
			(min_thickness 0.25)
			(keepout
				(tracks not_allowed)
				(vias allowed)
				(pads allowed)
				(copperpour not_allowed)
				(footprints allowed)
			)
			(placement
				(enabled no)
				(sheetname "")
			)
			(fill
				(thermal_gap 0.5)
				(thermal_bridge_width 0.5)
				(island_removal_mode 0)
			)
			(polygon
				(pts
					(xy 416.433 -21.59) (xy 415.925 -21.59) (xy 415.925 -21.971) (xy 416.433 -21.971)
				)
			)
		)
	)
	(footprint ""
		(layer "B.Cu")
		(at -1.3208 -114.1349 -90)
		(property "Reference" "C9M9"
			(at 0 0 90)
			(layer "B.SilkS")
			(hide yes)
			(effects
				(font
					(size 1.27 1.27)
				)
				(justify mirror)
			)
		)
		(property "Value" ""
			(at 0 0 90)
			(layer "B.Fab")
			(effects
				(font
					(size 1.27 1.27)
				)
				(justify mirror)
			)
		)
		(duplicate_pad_numbers_are_jumpers no)
		(fp_rect
			(start 0.3048 0.9906)
			(end -0.3048 -0.1016)
			(stroke
				(width 0)
				(type default)
			)
			(fill no)
			(layer "B.CrtYd")
		)
		(fp_line
			(start -0.3048 0.9906)
			(end -0.3048 -0.1016)
			(stroke
				(width 0.1)
				(type default)
			)
			(layer "B.Fab")
		)
		(fp_line
			(start 0.3048 0.9906)
			(end -0.3048 0.9906)
			(stroke
				(width 0.1)
				(type default)
			)
			(layer "B.Fab")
		)
		(fp_line
			(start -0.3048 -0.1016)
			(end 0.3048 -0.1016)
			(stroke
				(width 0.1)
				(type default)
			)
			(layer "B.Fab")
		)
		(fp_line
			(start 0.3048 -0.1016)
			(end 0.3048 0.9906)
			(stroke
				(width 0.1)
				(type default)
			)
			(layer "B.Fab")
		)
		(pad "1" smd rect
			(at 0 0 90)
			(size 0.508 0.508)
			(layers "B.Cu" "B.Mask" "B.Paste")
			(net "P12V_STBY")
		)
		(pad "2" smd rect
			(at 0 0.889 90)
			(size 0.508 0.508)
			(layers "B.Cu" "B.Mask" "B.Paste")
			(net "GND")
		)
		(zone
			(layer "B.Cu")
			(hatch none 0.5)
			(connect_pads
				(clearance 0)
			)
			(min_thickness 0.25)
			(keepout
				(tracks allowed)
				(vias not_allowed)
				(pads allowed)
				(copperpour not_allowed)
				(footprints allowed)
			)
			(placement
				(enabled no)
				(sheetname "")
			)
			(fill
				(thermal_gap 0.5)
				(thermal_bridge_width 0.5)
				(island_removal_mode 0)
			)
			(polygon
				(pts
					(xy -1.9558 -113.8809) (xy -1.5748 -113.8809) (xy -1.5748 -114.3889) (xy -1.9558 -114.3889)
				)
			)
		)
		(zone
			(layer "B.Cu")
			(hatch none 0.5)
			(connect_pads
				(clearance 0)
			)
			(min_thickness 0.25)
			(keepout
				(tracks not_allowed)
				(vias allowed)
				(pads allowed)
				(copperpour not_allowed)
				(footprints allowed)
			)
			(placement
				(enabled no)
				(sheetname "")
			)
			(fill
				(thermal_gap 0.5)
				(thermal_bridge_width 0.5)
				(island_removal_mode 0)
			)
			(polygon
				(pts
					(xy -1.9558 -113.8809) (xy -1.5748 -113.8809) (xy -1.5748 -114.3889) (xy -1.9558 -114.3889)
				)
			)
		)
	)
)
